(kicad_pcb
	(version 20241229)
	(generator "pcbnew")
	(generator_version "9.0")
	(general
		(thickness 1.6296)
		(legacy_teardrops no)
	)
	(paper "A3")
	(title_block
		(title "Thunderbolt to 10GbE adapter")
		(date "2026-04-21")
		(rev "1.1.0")
		(company "Antmicro Ltd")
		(comment 1 "www.antmicro.com")
		(comment 9 "footprints 352-355 of 703")
	)
	(layers
		(0 "F.Cu" signal)
		(4 "In1.Cu" signal)
		(6 "In2.Cu" signal)
		(8 "In3.Cu" signal)
		(10 "In4.Cu" signal)
		(12 "In5.Cu" signal)
		(14 "In6.Cu" signal)
		(2 "B.Cu" signal)
		(9 "F.Adhes" user "F.Adhesive")
		(11 "B.Adhes" user "B.Adhesive")
		(13 "F.Paste" user)
		(15 "B.Paste" user)
		(5 "F.SilkS" user "F.Silkscreen")
		(7 "B.SilkS" user "B.Silkscreen")
		(1 "F.Mask" user)
		(3 "B.Mask" user)
		(17 "Dwgs.User" user "User.Drawings")
		(19 "Cmts.User" user "User.Comments")
		(21 "Eco1.User" user "User.Eco1")
		(23 "Eco2.User" user "User.Eco2")
		(25 "Edge.Cuts" user)
		(27 "Margin" user)
		(31 "F.CrtYd" user "F.Courtyard")
		(29 "B.CrtYd" user "B.Courtyard")
		(35 "F.Fab" user)
		(33 "B.Fab" user)
	)
	(footprint "antmicro-footprints:C_0402_1005Metric"
		(layer "F.Cu")
		(at 138 75.75)
		(descr "Capacitor SMD 0402")
		(tags "capacitor SMD 0402")
		(property "Reference" "C267"
			(at -3.8 0.45 0)
			(layer "F.SilkS")
			(effects
				(font
					(size 0.7 0.7)
					(thickness 0.15)
				)
				(justify left bottom)
			)
		)
		(property "Value" "C_220n_16V_0402"
			(at -1.022927 2.155213 0)
			(layer "F.Fab")
			(effects
				(font
					(size 0.7 0.7)
					(thickness 0.15)
				)
				(justify left bottom)
			)
		)
		(property "Datasheet" "https://www.murata.com/products/productdetail?partno=GRM155R71C224KA12%23"
			(at 0 0 0)
			(layer "F.Fab")
			(hide yes)
			(effects
				(font
					(size 1.27 1.27)
					(thickness 0.15)
				)
			)
		)
		(property "Description" "SMD Multilayer Ceramic Capacitor, 0.22 µF, 16 V, 0402 [1005 Metric], ± 10%, X7R, GRM Series"
			(at 0 0 0)
			(layer "F.Fab")
			(hide yes)
			(effects
				(font
					(size 1.27 1.27)
					(thickness 0.15)
				)
			)
		)
		(property "MPN" "GRM155R71C224KA12D"
			(at 0 0 0)
			(unlocked yes)
			(layer "F.Fab")
			(hide yes)
			(effects
				(font
					(size 1 1)
					(thickness 0.15)
				)
			)
		)
		(property "Manufacturer" "Murata"
			(at 0 0 0)
			(unlocked yes)
			(layer "F.Fab")
			(hide yes)
			(effects
				(font
					(size 1 1)
					(thickness 0.15)
				)
			)
		)
		(property "License" "Apache-2.0"
			(at 0 0 0)
			(unlocked yes)
			(layer "F.Fab")
			(hide yes)
			(effects
				(font
					(size 1 1)
					(thickness 0.15)
				)
			)
		)
		(property "Author" "Antmicro"
			(at 0 0 0)
			(unlocked yes)
			(layer "F.Fab")
			(hide yes)
			(effects
				(font
					(size 1 1)
					(thickness 0.15)
				)
			)
		)
		(property "Val" "220n"
			(at 0 0 0)
			(unlocked yes)
			(layer "F.Fab")
			(hide yes)
			(effects
				(font
					(size 1 1)
					(thickness 0.15)
				)
			)
		)
		(property "Voltage" "16V"
			(at 0 0 0)
			(unlocked yes)
			(layer "F.Fab")
			(hide yes)
			(effects
				(font
					(size 1 1)
					(thickness 0.15)
				)
			)
		)
		(property "Dielectric" "X7R"
			(at 0 0 0)
			(unlocked yes)
			(layer "F.Fab")
			(hide yes)
			(effects
				(font
					(size 1 1)
					(thickness 0.15)
				)
			)
		)
		(sheetname "/X710-AT2 PCIe/")
		(sheetfile "x710-at2-pcie.kicad_sch")
		(attr smd)
		(fp_rect
			(start -0.925 -0.47)
			(end 0.925 0.47)
			(stroke
				(width 0.05)
				(type default)
			)
			(fill no)
			(layer "F.CrtYd")
		)
		(fp_line
			(start -0.494 -0.25)
			(end 0.504 -0.25)
			(stroke
				(width 0.15)
				(type solid)
			)
			(layer "F.Fab")
		)
		(fp_line
			(start -0.494 0.248)
			(end -0.494 -0.25)
			(stroke
				(width 0.15)
				(type solid)
			)
			(layer "F.Fab")
		)
		(fp_line
			(start 0.504 -0.25)
			(end 0.504 0.248)
			(stroke
				(width 0.15)
				(type solid)
			)
			(layer "F.Fab")
		)
		(fp_line
			(start 0.504 0.248)
			(end -0.494 0.248)
			(stroke
				(width 0.15)
				(type solid)
			)
			(layer "F.Fab")
		)
		(fp_text user "License: Apache-2.0"
			(at -0.939 5.799 0)
			(layer "F.Fab")
			(effects
				(font
					(size 0.7 0.7)
					(thickness 0.15)
				)
				(justify left bottom)
			)
		)
		(fp_text user "${REFERENCE}"
			(at -0.939 4.599 0)
			(layer "F.Fab")
			(effects
				(font
					(size 0.7 0.7)
					(thickness 0.15)
				)
				(justify left bottom)
			)
		)
		(fp_text user "Author: Antmicro"
			(at -0.939 3.399 0)
			(layer "F.Fab")
			(effects
				(font
					(size 0.7 0.7)
					(thickness 0.15)
				)
				(justify left bottom)
			)
		)
		(pad "1" smd roundrect
			(at -0.48 0)
			(size 0.59 0.64)
			(layers "F.Cu" "F.Mask" "F.Paste")
			(roundrect_rratio 0.25)
			(net 599 "/TB Controller/PCIex4.TX1-")
			(pintype "passive")
		)
		(pad "2" smd roundrect
			(at 0.48 0)
			(size 0.59 0.64)
			(layers "F.Cu" "F.Mask" "F.Paste")
			(roundrect_rratio 0.25)
			(net 30 "/X710-AT2 PCIe/PCIe_{x4}_AC.TX1-")
			(pintype "passive")
		)
	)
	(footprint "antmicro-footprints:SOT-23-3"
		(layer "F.Cu")
		(at 155 117.5 180)
		(property "Reference" "Q6"
			(at 2.4 0.5 180)
			(layer "F.SilkS")
			(effects
				(font
					(size 0.7 0.7)
					(thickness 0.15)
				)
				(justify left bottom)
			)
		)
		(property "Value" "2N7002_SOT-23-3"
			(at -1.9 2.7 180)
			(layer "F.Fab")
			(effects
				(font
					(size 0.7 0.7)
					(thickness 0.15)
				)
				(justify left bottom)
			)
		)
		(property "Datasheet" "https://www.onsemi.com/pub/Collateral/NDS7002A-D.PDF"
			(at 0 0 180)
			(layer "F.Fab")
			(hide yes)
			(effects
				(font
					(size 1.27 1.27)
					(thickness 0.15)
				)
			)
		)
		(property "Description" "Power MOSFET, N Channel, 60 V, 115 mA, 1.2 ohm, SOT-23, Surface Mount"
			(at 0 0 180)
			(layer "F.Fab")
			(hide yes)
			(effects
				(font
					(size 1.27 1.27)
					(thickness 0.15)
				)
			)
		)
		(property "MPN" "2N7002"
			(at 0 0 180)
			(unlocked yes)
			(layer "F.Fab")
			(hide yes)
			(effects
				(font
					(size 1 1)
					(thickness 0.15)
				)
			)
		)
		(property "Manufacturer" "ON Semiconductor"
			(at 0 0 180)
			(unlocked yes)
			(layer "F.Fab")
			(hide yes)
			(effects
				(font
					(size 1 1)
					(thickness 0.15)
				)
			)
		)
		(property "Author" "Antmicro"
			(at 0 0 180)
			(unlocked yes)
			(layer "F.Fab")
			(hide yes)
			(effects
				(font
					(size 1 1)
					(thickness 0.15)
				)
			)
		)
		(property "License" "Apache-2.0"
			(at 0 0 180)
			(unlocked yes)
			(layer "F.Fab")
			(hide yes)
			(effects
				(font
					(size 1 1)
					(thickness 0.15)
				)
			)
		)
		(sheetname "/X710 DCDC converters/")
		(sheetfile "DCDC_converters_X710.kicad_sch")
		(attr smd)
		(fp_line
			(start 0.7 1.5)
			(end -0.7 1.5)
			(stroke
				(width 0.15)
				(type solid)
			)
			(layer "F.SilkS")
		)
		(fp_line
			(start 0.7 0.4)
			(end 0.7 1.5)
			(stroke
				(width 0.15)
				(type solid)
			)
			(layer "F.SilkS")
		)
		(fp_line
			(start 0.7 -0.4)
			(end 0.7 -1.5)
			(stroke
				(width 0.15)
				(type solid)
			)
			(layer "F.SilkS")
		)
		(fp_line
			(start 0.7 -1.5)
			(end -0.7 -1.5)
			(stroke
				(width 0.15)
				(type solid)
			)
			(layer "F.SilkS")
		)
		(fp_line
			(start -0.7 1.5)
			(end -0.7 1.35)
			(stroke
				(width 0.15)
				(type solid)
			)
			(layer "F.SilkS")
		)
		(fp_line
			(start -0.85 -1.35)
			(end -0.7 -1.5)
			(stroke
				(width 0.15)
				(type solid)
			)
			(layer "F.SilkS")
		)
		(fp_line
			(start -1.45 -1.35)
			(end -0.85 -1.35)
			(stroke
				(width 0.15)
				(type solid)
			)
			(layer "F.SilkS")
		)
		(fp_line
			(start 1.75 0.45)
			(end 0.85 0.45)
			(stroke
				(width 0.05)
				(type solid)
			)
			(layer "F.CrtYd")
		)
		(fp_line
			(start 1.75 -0.45)
			(end 1.75 0.45)
			(stroke
				(width 0.05)
				(type solid)
			)
			(layer "F.CrtYd")
		)
		(fp_line
			(start 0.85 1.65)
			(end -0.85 1.65)
			(stroke
				(width 0.05)
				(type solid)
			)
			(layer "F.CrtYd")
		)
		(fp_line
			(start 0.85 0.45)
			(end 0.85 1.65)
			(stroke
				(width 0.05)
				(type solid)
			)
			(layer "F.CrtYd")
		)
		(fp_line
			(start 0.825 -0.45)
			(end 1.75 -0.45)
			(stroke
				(width 0.05)
				(type solid)
			)
			(layer "F.CrtYd")
		)
		(fp_line
			(start 0.825 -1.6)
			(end 0.825 -0.45)
			(stroke
				(width 0.05)
				(type solid)
			)
			(layer "F.CrtYd")
		)
		(fp_line
			(start -0.85 1.65)
			(end -0.85 1.4)
			(stroke
				(width 0.05)
				(type solid)
			)
			(layer "F.CrtYd")
		)
		(fp_line
			(start -0.85 1.4)
			(end -1.75 1.4)
			(stroke
				(width 0.05)
				(type solid)
			)
			(layer "F.CrtYd")
		)
		(fp_line
			(start -0.85 0.5)
			(end -0.85 -0.5)
			(stroke
				(width 0.05)
				(type solid)
			)
			(layer "F.CrtYd")
		)
		(fp_line
			(start -0.85 -0.5)
			(end -1.75 -0.5)
			(stroke
				(width 0.05)
				(type solid)
			)
			(layer "F.CrtYd")
		)
		(fp_line
			(start -0.9 -1.4)
			(end -1.75 -1.4)
			(stroke
				(width 0.05)
				(type solid)
			)
			(layer "F.CrtYd")
		)
		(fp_line
			(start -0.9 -1.6)
			(end 0.825 -1.6)
			(stroke
				(width 0.05)
				(type solid)
			)
			(layer "F.CrtYd")
		)
		(fp_line
			(start -0.9 -1.6)
			(end -0.9 -1.4)
			(stroke
				(width 0.05)
				(type solid)
			)
			(layer "F.CrtYd")
		)
		(fp_line
			(start -1.75 1.4)
			(end -1.75 0.5)
			(stroke
				(width 0.05)
				(type solid)
			)
			(layer "F.CrtYd")
		)
		(fp_line
			(start -1.75 0.5)
			(end -0.85 0.5)
			(stroke
				(width 0.05)
				(type solid)
			)
			(layer "F.CrtYd")
		)
		(fp_line
			(start -1.75 -0.5)
			(end -1.75 -1.4)
			(stroke
				(width 0.05)
				(type solid)
			)
			(layer "F.CrtYd")
		)
		(fp_line
			(start 0.688 1.519)
			(end 0.688 -1.52)
			(stroke
				(width 0.15)
				(type solid)
			)
			(layer "F.Fab")
		)
		(fp_line
			(start -0.437 -1.526)
			(end 0.688 -1.526)
			(stroke
				(width 0.15)
				(type solid)
			)
			(layer "F.Fab")
		)
		(fp_line
			(start -0.437 -1.526)
			(end -0.712 -1.325)
			(stroke
				(width 0.15)
				(type solid)
			)
			(layer "F.Fab")
		)
		(fp_line
			(start -0.712 1.519)
			(end 0.688 1.519)
			(stroke
				(width 0.15)
				(type solid)
			)
			(layer "F.Fab")
		)
		(fp_line
			(start -0.712 -1.325)
			(end -0.712 1.523)
			(stroke
				(width 0.15)
				(type solid)
			)
			(layer "F.Fab")
		)
		(fp_text user "Author: Antmicro"
			(at -1.837 5.3 180)
			(layer "F.Fab")
			(effects
				(font
					(size 0.7 0.7)
					(thickness 0.15)
				)
				(justify left bottom)
			)
		)
		(fp_text user "${REFERENCE}"
			(at -1.837 4 180)
			(layer "F.Fab")
			(effects
				(font
					(size 0.7 0.7)
					(thickness 0.15)
				)
				(justify left bottom)
			)
		)
		(fp_text user "License: Apache-2.0"
			(at -1.8 6.8 180)
			(layer "F.Fab")
			(effects
				(font
					(size 0.7 0.7)
					(thickness 0.15)
				)
				(justify left bottom)
			)
		)
		(pad "1" smd roundrect
			(at -1.1 -0.951 180)
			(size 1 0.6)
			(layers "F.Cu" "F.Mask" "F.Paste")
			(roundrect_rratio 0.15)
			(net 355 "/X710 DCDC converters/DVDD_PG")
			(pinfunction "G")
			(pintype "input")
		)
		(pad "2" smd roundrect
			(at -1.1 0.949 180)
			(size 1 0.6)
			(layers "F.Cu" "F.Mask" "F.Paste")
			(roundrect_rratio 0.15)
			(net 23 "GND")
			(pinfunction "S")
			(pintype "passive")
		)
		(pad "3" smd roundrect
			(at 1.1 -0.0005 180)
			(size 1 0.6)
			(layers "F.Cu" "F.Mask" "F.Paste")
			(roundrect_rratio 0.15)
			(net 418 "Net-(D11-C)")
			(pinfunction "D")
			(pintype "passive")
		)
	)
	(footprint "antmicro-footprints:C_0402_1005Metric"
		(layer "F.Cu")
		(at 136.25 93.75)
		(descr "Capacitor SMD 0402")
		(tags "capacitor SMD 0402")
		(property "Reference" "C149"
			(at 37.604999 -9.199999 0)
			(layer "F.SilkS")
			(effects
				(font
					(size 0.7 0.7)
					(thickness 0.15)
				)
			)
		)
		(property "Value" "C_100n_0402"
			(at -1.022927 2.155213 0)
			(layer "F.Fab")
			(effects
				(font
					(size 0.7 0.7)
					(thickness 0.15)
				)
				(justify left bottom)
			)
		)
		(property "Datasheet" "https://www.murata.com/products/productdetail?partno=GRM155R61H104KE14%23"
			(at 0 0 0)
			(layer "F.Fab")
			(hide yes)
			(effects
				(font
					(size 1.27 1.27)
					(thickness 0.15)
				)
			)
		)
		(property "Description" "SMD Multilayer Ceramic Capacitor, 0.1 µF, 50 V, 0402 [1005 Metric], ± 10%, X5R, GRM Series"
			(at 0 0 0)
			(layer "F.Fab")
			(hide yes)
			(effects
				(font
					(size 1.27 1.27)
					(thickness 0.15)
				)
			)
		)
		(property "MPN" "GRM155R61H104KE14D"
			(at 0 0 0)
			(unlocked yes)
			(layer "F.Fab")
			(hide yes)
			(effects
				(font
					(size 1 1)
					(thickness 0.15)
				)
			)
		)
		(property "Manufacturer" "Murata"
			(at 0 0 0)
			(unlocked yes)
			(layer "F.Fab")
			(hide yes)
			(effects
				(font
					(size 1 1)
					(thickness 0.15)
				)
			)
		)
		(property "License" "Apache-2.0"
			(at 0 0 0)
			(unlocked yes)
			(layer "F.Fab")
			(hide yes)
			(effects
				(font
					(size 1 1)
					(thickness 0.15)
				)
			)
		)
		(property "Author" "Antmicro"
			(at 0 0 0)
			(unlocked yes)
			(layer "F.Fab")
			(hide yes)
			(effects
				(font
					(size 1 1)
					(thickness 0.15)
				)
			)
		)
		(property "Val" "100n"
			(at 0 0 0)
			(unlocked yes)
			(layer "F.Fab")
			(hide yes)
			(effects
				(font
					(size 1 1)
					(thickness 0.15)
				)
			)
		)
		(property "Voltage" "50V"
			(at 0 0 0)
			(unlocked yes)
			(layer "F.Fab")
			(hide yes)
			(effects
				(font
					(size 1 1)
					(thickness 0.15)
				)
			)
		)
		(property "Dielectric" "X5R"
			(at 0 0 0)
			(unlocked yes)
			(layer "F.Fab")
			(hide yes)
			(effects
				(font
					(size 1 1)
					(thickness 0.15)
				)
			)
		)
		(sheetname "/X710 DCDC converters/")
		(sheetfile "DCDC_converters_X710.kicad_sch")
		(attr smd)
		(fp_rect
			(start -0.925 -0.47)
			(end 0.925 0.47)
			(stroke
				(width 0.05)
				(type default)
			)
			(fill no)
			(layer "F.CrtYd")
		)
		(fp_line
			(start -0.494 -0.25)
			(end 0.504 -0.25)
			(stroke
				(width 0.15)
				(type solid)
			)
			(layer "F.Fab")
		)
		(fp_line
			(start -0.494 0.248)
			(end -0.494 -0.25)
			(stroke
				(width 0.15)
				(type solid)
			)
			(layer "F.Fab")
		)
		(fp_line
			(start 0.504 -0.25)
			(end 0.504 0.248)
			(stroke
				(width 0.15)
				(type solid)
			)
			(layer "F.Fab")
		)
		(fp_line
			(start 0.504 0.248)
			(end -0.494 0.248)
			(stroke
				(width 0.15)
				(type solid)
			)
			(layer "F.Fab")
		)
		(fp_text user "${REFERENCE}"
			(at -0.939 4.599 0)
			(layer "F.Fab")
			(effects
				(font
					(size 0.7 0.7)
					(thickness 0.15)
				)
				(justify left bottom)
			)
		)
		(fp_text user "Author: Antmicro"
			(at -0.939 3.399 0)
			(layer "F.Fab")
			(effects
				(font
					(size 0.7 0.7)
					(thickness 0.15)
				)
				(justify left bottom)
			)
		)
		(fp_text user "License: Apache-2.0"
			(at -0.939 5.799 0)
			(layer "F.Fab")
			(effects
				(font
					(size 0.7 0.7)
					(thickness 0.15)
				)
				(justify left bottom)
			)
		)
		(pad "1" smd roundrect
			(at -0.48 0)
			(size 0.59 0.64)
			(layers "F.Cu" "F.Mask" "F.Paste")
			(roundrect_rratio 0.25)
			(net 23 "GND")
			(pintype "passive")
		)
		(pad "2" smd roundrect
			(at 0.48 0)
			(size 0.59 0.64)
			(layers "F.Cu" "F.Mask" "F.Paste")
			(roundrect_rratio 0.25)
			(net 334 "/X710 DCDC converters/+3V3_OUT")
			(pintype "passive")
		)
	)
	(footprint "antmicro-footprints:C_0603_1608Metric"
		(layer "F.Cu")
		(at 122.15 106.1)
		(descr "Capacitor SMD 0603")
		(tags "capacitor 0603")
		(property "Reference" "C27"
			(at 2.35 -1.1 0)
			(layer "F.SilkS")
			(effects
				(font
					(size 0.7 0.7)
					(thickness 0.15)
				)
			)
		)
		(property "Value" "C_22u_0603"
			(at -1.42757 1.770288 0)
			(layer "F.Fab")
			(effects
				(font
					(size 0.7 0.7)
					(thickness 0.15)
				)
				(justify left bottom)
			)
		)
		(property "Datasheet" "https://www.murata.com/products/productdetail?partno=GRM188R60J226MEA0%23"
			(at 0 0 0)
			(layer "F.Fab")
			(hide yes)
			(effects
				(font
					(size 1.27 1.27)
					(thickness 0.15)
				)
			)
		)
		(property "Description" "SMD Multilayer Ceramic Capacitor, 22 µF, 6.3 V, 0603 [1608 Metric], ± 20%, X5R, GRM Series"
			(at 0 0 0)
			(layer "F.Fab")
			(hide yes)
			(effects
				(font
					(size 1.27 1.27)
					(thickness 0.15)
				)
			)
		)
		(property "MPN" "GRM188R60J226MEA0D"
			(at 0 0 0)
			(unlocked yes)
			(layer "F.Fab")
			(hide yes)
			(effects
				(font
					(size 1 1)
					(thickness 0.15)
				)
			)
		)
		(property "Manufacturer" "Murata"
			(at 0 0 0)
			(unlocked yes)
			(layer "F.Fab")
			(hide yes)
			(effects
				(font
					(size 1 1)
					(thickness 0.15)
				)
			)
		)
		(property "License" "Apache-2.0"
			(at 0 0 0)
			(unlocked yes)
			(layer "F.Fab")
			(hide yes)
			(effects
				(font
					(size 1 1)
					(thickness 0.15)
				)
			)
		)
		(property "Val" "22u"
			(at 0 0 0)
			(unlocked yes)
			(layer "F.Fab")
			(hide yes)
			(effects
				(font
					(size 1 1)
					(thickness 0.15)
				)
			)
		)
		(property "Voltage" ""
			(at 0 0 0)
			(unlocked yes)
			(layer "F.Fab")
			(hide yes)
			(effects
				(font
					(size 1 1)
					(thickness 0.15)
				)
			)
		)
		(property "Dielectric" ""
			(at 0 0 0)
			(unlocked yes)
			(layer "F.Fab")
			(hide yes)
			(effects
				(font
					(size 1 1)
					(thickness 0.15)
				)
			)
		)
		(property "Author" "Antmicro"
			(at 0 0 0)
			(unlocked yes)
			(layer "F.Fab")
			(hide yes)
			(effects
				(font
					(size 1 1)
					(thickness 0.15)
				)
			)
		)
		(sheetname "/PD and TB DC-DC/")
		(sheetfile "PD_and_TB_DC_DC.kicad_sch")
		(attr smd)
		(fp_line
			(start -0.15 -0.4)
			(end 0.15 -0.4)
			(stroke
				(width 0.15)
				(type solid)
			)
			(layer "F.SilkS")
		)
		(fp_line
			(start -0.15 0.4)
			(end 0.15 0.4)
			(stroke
				(width 0.15)
				(type solid)
			)
			(layer "F.SilkS")
		)
		(fp_rect
			(start -1.25 -0.65)
			(end 1.25 0.65)
			(stroke
				(width 0.05)
				(type solid)
			)
			(fill no)
			(layer "F.CrtYd")
		)
		(fp_rect
			(start -0.8 -0.4)
			(end 0.8 0.4)
			(stroke
				(width 0.15)
				(type solid)
			)
			(fill no)
			(layer "F.Fab")
		)
		(fp_text user "${REFERENCE}"
			(at -1.682 3.895 0)
			(layer "F.Fab")
			(effects
				(font
					(size 0.7 0.7)
					(thickness 0.15)
				)
				(justify left bottom)
			)
		)
		(fp_text user "License: Apache-2.0"
			(at -1.682 5.895 0)
			(layer "F.Fab")
			(effects
				(font
					(size 0.7 0.7)
					(thickness 0.15)
				)
				(justify left bottom)
			)
		)
		(fp_text user "Author: Antmicro"
			(at -1.682 4.894 0)
			(layer "F.Fab")
			(effects
				(font
					(size 0.7 0.7)
					(thickness 0.15)
				)
				(justify left bottom)
			)
		)
		(pad "1" smd roundrect
			(at -0.7 0)
			(size 0.8 1)
			(layers "F.Cu" "F.Mask" "F.Paste")
			(roundrect_rratio 0.2)
			(net 23 "GND")
			(pintype "passive")
		)
		(pad "2" smd roundrect
			(at 0.7 0)
			(size 0.8 1)
			(layers "F.Cu" "F.Mask" "F.Paste")
			(roundrect_rratio 0.2)
			(net 399 "Net-(D4-A)")
			(pintype "passive")
		)
	)
)
